(kicad_pcb
	(version 20260206)
	(generator "pcbnew")
	(generator_version "10.0")
	(general
		(thickness 1.6)
		(legacy_teardrops no)
	)
	(paper "A4")
	(title_block
		(title "03242023_DA0F0TMBIJ0_F0T_Motherboard_J_brd_V01_OCP.brd")
		(comment 1 "Grand Teton / footprints 4053-4058 of 6105")
	)
	(layers
		(0 "F.Cu" signal "TOP")
		(4 "In1.Cu" signal "GND")
		(6 "In2.Cu" signal "IN1")
		(8 "In3.Cu" signal "GND1")
		(10 "In4.Cu" signal "IN2")
		(12 "In5.Cu" signal "GND2")
		(14 "In6.Cu" signal "IN3")
		(16 "In7.Cu" signal "GND3")
		(18 "In8.Cu" signal "VCC")
		(20 "In9.Cu" signal "VCC1")
		(22 "In10.Cu" signal "GND4")
		(24 "In11.Cu" signal "IN4")
		(26 "In12.Cu" signal "GND5")
		(28 "In13.Cu" signal "IN5")
		(30 "In14.Cu" signal "GND6")
		(32 "In15.Cu" signal "IN6")
		(34 "In16.Cu" signal "GND7")
		(2 "B.Cu" signal "BOTTOM")
		(9 "F.Adhes" user "F.Adhesive")
		(11 "B.Adhes" user "B.Adhesive")
		(13 "F.Paste" user "Package Geometry/Pastemask Top")
		(15 "B.Paste" user "Package Geometry/Pastemask Bottom")
		(5 "F.SilkS" user "Ref Des/Silkscreen Top")
		(7 "B.SilkS" user "Ref Des/Silkscreen Bottom")
		(1 "F.Mask" user "Board Geometry/Soldermask Top")
		(3 "B.Mask" user "Board Geometry/Soldermask Bottom")
		(17 "Dwgs.User" user "User.Drawings")
		(19 "Cmts.User" user "User.Comments")
		(21 "Eco1.User" user "User.Eco1")
		(23 "Eco2.User" user "User.Eco2")
		(25 "Edge.Cuts" user "Board Geometry/Outline")
		(27 "Margin" user)
		(31 "F.CrtYd" user "Package Geometry/Place Bound Top")
		(29 "B.CrtYd" user "Package Geometry/Place Bound Bottom")
		(35 "F.Fab" user "Ref Des/Assembly Top")
		(33 "B.Fab" user "Ref Des/Assembly Bottom")
	)
	(footprint ""
		(layer "F.Cu")
		(at 348.390464 -356.478332 180)
		(property "Reference" "R2590"
			(at 0 0 180)
			(layer "F.SilkS")
			(hide yes)
			(effects
				(font
					(size 1.27 1.27)
				)
			)
		)
		(property "Value" ""
			(at 0 0 180)
			(layer "F.Fab")
			(effects
				(font
					(size 1.27 1.27)
				)
			)
		)
		(duplicate_pad_numbers_are_jumpers no)
		(fp_line
			(start 0.7874 0.4064)
			(end -0.7874 0.4064)
			(stroke
				(width 0.1524)
				(type default)
			)
			(layer "F.SilkS")
		)
		(fp_line
			(start 0.7874 -0.4064)
			(end 0.7874 0.4064)
			(stroke
				(width 0.1524)
				(type default)
			)
			(layer "F.SilkS")
		)
		(fp_line
			(start -0.7874 0.4064)
			(end -0.7874 -0.4064)
			(stroke
				(width 0.1524)
				(type default)
			)
			(layer "F.SilkS")
		)
		(fp_line
			(start -0.7874 -0.4064)
			(end 0.7874 -0.4064)
			(stroke
				(width 0.1524)
				(type default)
			)
			(layer "F.SilkS")
		)
		(fp_line
			(start 0.67945 0.3048)
			(end 0.120396 0.3048)
			(stroke
				(width 0.1)
				(type default)
			)
			(layer "F.Fab")
		)
		(fp_line
			(start 0.67945 -0.3048)
			(end 0.67945 0.3048)
			(stroke
				(width 0.1)
				(type default)
			)
			(layer "F.Fab")
		)
		(fp_line
			(start 0.12065 -0.2794)
			(end 0.12065 -0.3048)
			(stroke
				(width 0.1)
				(type default)
			)
			(layer "F.Fab")
		)
		(fp_line
			(start 0.12065 -0.3048)
			(end 0.67945 -0.3048)
			(stroke
				(width 0.1)
				(type default)
			)
			(layer "F.Fab")
		)
		(fp_line
			(start 0.120396 0.3048)
			(end 0.120396 0.2794)
			(stroke
				(width 0.1)
				(type default)
			)
			(layer "F.Fab")
		)
		(fp_line
			(start 0.120396 0.2794)
			(end -0.12065 0.2794)
			(stroke
				(width 0.1)
				(type default)
			)
			(layer "F.Fab")
		)
		(fp_line
			(start -0.12065 0.3048)
			(end -0.67945 0.3048)
			(stroke
				(width 0.1)
				(type default)
			)
			(layer "F.Fab")
		)
		(fp_line
			(start -0.12065 0.2794)
			(end -0.12065 0.3048)
			(stroke
				(width 0.1)
				(type default)
			)
			(layer "F.Fab")
		)
		(fp_line
			(start -0.12065 -0.2794)
			(end 0.12065 -0.2794)
			(stroke
				(width 0.1)
				(type default)
			)
			(layer "F.Fab")
		)
		(fp_line
			(start -0.12065 -0.305054)
			(end -0.12065 -0.2794)
			(stroke
				(width 0.1)
				(type default)
			)
			(layer "F.Fab")
		)
		(fp_line
			(start -0.67945 0.3048)
			(end -0.67945 -0.305054)
			(stroke
				(width 0.1)
				(type default)
			)
			(layer "F.Fab")
		)
		(fp_line
			(start -0.67945 -0.305054)
			(end -0.12065 -0.305054)
			(stroke
				(width 0.1)
				(type default)
			)
			(layer "F.Fab")
		)
		(pad "1" smd circle
			(at -0.40005 0 180)
			(size 0 0)
			(layers "F.Cu" "F.Mask" "F.Paste")
			(net "SVID_DIO0_CPU0_R")
		)
		(pad "2" smd circle
			(at 0.40005 0 180)
			(size 0 0)
			(layers "F.Cu" "F.Mask" "F.Paste")
			(net "PVNN_TERM_CPU0")
		)
	)
	(footprint ""
		(layer "F.Cu")
		(at 262.450072 -127.965708 -90)
		(property "Reference" "R4480"
			(at 0 0 270)
			(layer "F.SilkS")
			(hide yes)
			(effects
				(font
					(size 1.27 1.27)
				)
			)
		)
		(property "Value" ""
			(at 0 0 270)
			(layer "F.Fab")
			(effects
				(font
					(size 1.27 1.27)
				)
			)
		)
		(duplicate_pad_numbers_are_jumpers no)
		(fp_line
			(start -0.7874 0.4064)
			(end -0.7874 -0.4064)
			(stroke
				(width 0.1524)
				(type default)
			)
			(layer "F.SilkS")
		)
		(fp_line
			(start 0.7874 0.4064)
			(end -0.7874 0.4064)
			(stroke
				(width 0.1524)
				(type default)
			)
			(layer "F.SilkS")
		)
		(fp_line
			(start -0.7874 -0.4064)
			(end 0.7874 -0.4064)
			(stroke
				(width 0.1524)
				(type default)
			)
			(layer "F.SilkS")
		)
		(fp_line
			(start 0.7874 -0.4064)
			(end 0.7874 0.4064)
			(stroke
				(width 0.1524)
				(type default)
			)
			(layer "F.SilkS")
		)
		(fp_line
			(start -0.67945 0.3048)
			(end -0.67945 -0.305054)
			(stroke
				(width 0.1)
				(type default)
			)
			(layer "F.Fab")
		)
		(fp_line
			(start -0.12065 0.3048)
			(end -0.67945 0.3048)
			(stroke
				(width 0.1)
				(type default)
			)
			(layer "F.Fab")
		)
		(fp_line
			(start 0.120396 0.3048)
			(end 0.120396 0.2794)
			(stroke
				(width 0.1)
				(type default)
			)
			(layer "F.Fab")
		)
		(fp_line
			(start 0.67945 0.3048)
			(end 0.120396 0.3048)
			(stroke
				(width 0.1)
				(type default)
			)
			(layer "F.Fab")
		)
		(fp_line
			(start -0.12065 0.2794)
			(end -0.12065 0.3048)
			(stroke
				(width 0.1)
				(type default)
			)
			(layer "F.Fab")
		)
		(fp_line
			(start 0.120396 0.2794)
			(end -0.12065 0.2794)
			(stroke
				(width 0.1)
				(type default)
			)
			(layer "F.Fab")
		)
		(fp_line
			(start -0.12065 -0.2794)
			(end 0.12065 -0.2794)
			(stroke
				(width 0.1)
				(type default)
			)
			(layer "F.Fab")
		)
		(fp_line
			(start 0.12065 -0.2794)
			(end 0.12065 -0.3048)
			(stroke
				(width 0.1)
				(type default)
			)
			(layer "F.Fab")
		)
		(fp_line
			(start 0.12065 -0.3048)
			(end 0.67945 -0.3048)
			(stroke
				(width 0.1)
				(type default)
			)
			(layer "F.Fab")
		)
		(fp_line
			(start 0.67945 -0.3048)
			(end 0.67945 0.3048)
			(stroke
				(width 0.1)
				(type default)
			)
			(layer "F.Fab")
		)
		(fp_line
			(start -0.67945 -0.305054)
			(end -0.12065 -0.305054)
			(stroke
				(width 0.1)
				(type default)
			)
			(layer "F.Fab")
		)
		(fp_line
			(start -0.12065 -0.305054)
			(end -0.12065 -0.2794)
			(stroke
				(width 0.1)
				(type default)
			)
			(layer "F.Fab")
		)
		(pad "1" smd circle
			(at -0.40005 0 270)
			(size 0 0)
			(layers "F.Cu" "F.Mask" "F.Paste")
			(net "SMB_HOST_CLK_BUF_ISO_3V3AUX_SCL")
		)
		(pad "2" smd circle
			(at 0.40005 0 270)
			(size 0 0)
			(layers "F.Cu" "F.Mask" "F.Paste")
			(net "SMB_HOST_9ZXL045_3V3AUX_SCL")
		)
	)
	(footprint ""
		(layer "F.Cu")
		(at 421.92448 -156.327348 -90)
		(property "Reference" "PR442"
			(at 0 0 270)
			(layer "F.SilkS")
			(hide yes)
			(effects
				(font
					(size 1.27 1.27)
				)
			)
		)
		(property "Value" ""
			(at 0 0 270)
			(layer "F.Fab")
			(effects
				(font
					(size 1.27 1.27)
				)
			)
		)
		(duplicate_pad_numbers_are_jumpers no)
		(fp_line
			(start -0.7874 0.4064)
			(end -0.7874 -0.4064)
			(stroke
				(width 0.1524)
				(type default)
			)
			(layer "F.SilkS")
		)
		(fp_line
			(start 0.7874 0.4064)
			(end -0.7874 0.4064)
			(stroke
				(width 0.1524)
				(type default)
			)
			(layer "F.SilkS")
		)
		(fp_line
			(start -0.7874 -0.4064)
			(end 0.7874 -0.4064)
			(stroke
				(width 0.1524)
				(type default)
			)
			(layer "F.SilkS")
		)
		(fp_line
			(start 0.7874 -0.4064)
			(end 0.7874 0.4064)
			(stroke
				(width 0.1524)
				(type default)
			)
			(layer "F.SilkS")
		)
		(fp_line
			(start -0.67945 0.3048)
			(end -0.67945 -0.305054)
			(stroke
				(width 0.1)
				(type default)
			)
			(layer "F.Fab")
		)
		(fp_line
			(start -0.12065 0.3048)
			(end -0.67945 0.3048)
			(stroke
				(width 0.1)
				(type default)
			)
			(layer "F.Fab")
		)
		(fp_line
			(start 0.120396 0.3048)
			(end 0.120396 0.2794)
			(stroke
				(width 0.1)
				(type default)
			)
			(layer "F.Fab")
		)
		(fp_line
			(start 0.67945 0.3048)
			(end 0.120396 0.3048)
			(stroke
				(width 0.1)
				(type default)
			)
			(layer "F.Fab")
		)
		(fp_line
			(start -0.12065 0.2794)
			(end -0.12065 0.3048)
			(stroke
				(width 0.1)
				(type default)
			)
			(layer "F.Fab")
		)
		(fp_line
			(start 0.120396 0.2794)
			(end -0.12065 0.2794)
			(stroke
				(width 0.1)
				(type default)
			)
			(layer "F.Fab")
		)
		(fp_line
			(start -0.12065 -0.2794)
			(end 0.12065 -0.2794)
			(stroke
				(width 0.1)
				(type default)
			)
			(layer "F.Fab")
		)
		(fp_line
			(start 0.12065 -0.2794)
			(end 0.12065 -0.3048)
			(stroke
				(width 0.1)
				(type default)
			)
			(layer "F.Fab")
		)
		(fp_line
			(start 0.12065 -0.3048)
			(end 0.67945 -0.3048)
			(stroke
				(width 0.1)
				(type default)
			)
			(layer "F.Fab")
		)
		(fp_line
			(start 0.67945 -0.3048)
			(end 0.67945 0.3048)
			(stroke
				(width 0.1)
				(type default)
			)
			(layer "F.Fab")
		)
		(fp_line
			(start -0.67945 -0.305054)
			(end -0.12065 -0.305054)
			(stroke
				(width 0.1)
				(type default)
			)
			(layer "F.Fab")
		)
		(fp_line
			(start -0.12065 -0.305054)
			(end -0.12065 -0.2794)
			(stroke
				(width 0.1)
				(type default)
			)
			(layer "F.Fab")
		)
		(pad "1" smd circle
			(at -0.40005 0 270)
			(size 0 0)
			(layers "F.Cu" "F.Mask" "F.Paste")
			(net "P5V")
		)
		(pad "2" smd circle
			(at 0.40005 0 270)
			(size 0 0)
			(layers "F.Cu" "F.Mask" "F.Paste")
			(net "PVCCFA_EHV_CPU0_PVCC")
		)
	)
	(footprint ""
		(layer "F.Cu")
		(at 355.229414 -252.956314 -90)
		(property "Reference" "C1010"
			(at 0 0 270)
			(layer "F.SilkS")
			(hide yes)
			(effects
				(font
					(size 1.27 1.27)
				)
			)
		)
		(property "Value" ""
			(at 0 0 270)
			(layer "F.Fab")
			(effects
				(font
					(size 1.27 1.27)
				)
			)
		)
		(duplicate_pad_numbers_are_jumpers no)
		(fp_line
			(start -0.7874 0.4064)
			(end -0.7874 -0.4064)
			(stroke
				(width 0.1524)
				(type default)
			)
			(layer "F.SilkS")
		)
		(fp_line
			(start 0.7874 0.4064)
			(end -0.7874 0.4064)
			(stroke
				(width 0.1524)
				(type default)
			)
			(layer "F.SilkS")
		)
		(fp_line
			(start -0.7874 -0.4064)
			(end 0.7874 -0.4064)
			(stroke
				(width 0.1524)
				(type default)
			)
			(layer "F.SilkS")
		)
		(fp_line
			(start 0.7874 -0.4064)
			(end 0.7874 0.4064)
			(stroke
				(width 0.1524)
				(type default)
			)
			(layer "F.SilkS")
		)
		(fp_line
			(start -0.67945 0.3048)
			(end -0.67945 -0.305054)
			(stroke
				(width 0.1)
				(type default)
			)
			(layer "F.Fab")
		)
		(fp_line
			(start -0.12065 0.3048)
			(end -0.67945 0.3048)
			(stroke
				(width 0.1)
				(type default)
			)
			(layer "F.Fab")
		)
		(fp_line
			(start 0.120396 0.3048)
			(end 0.120396 0.2794)
			(stroke
				(width 0.1)
				(type default)
			)
			(layer "F.Fab")
		)
		(fp_line
			(start 0.67945 0.3048)
			(end 0.120396 0.3048)
			(stroke
				(width 0.1)
				(type default)
			)
			(layer "F.Fab")
		)
		(fp_line
			(start -0.12065 0.2794)
			(end -0.12065 0.3048)
			(stroke
				(width 0.1)
				(type default)
			)
			(layer "F.Fab")
		)
		(fp_line
			(start 0.120396 0.2794)
			(end -0.12065 0.2794)
			(stroke
				(width 0.1)
				(type default)
			)
			(layer "F.Fab")
		)
		(fp_line
			(start -0.12065 -0.2794)
			(end 0.12065 -0.2794)
			(stroke
				(width 0.1)
				(type default)
			)
			(layer "F.Fab")
		)
		(fp_line
			(start 0.12065 -0.2794)
			(end 0.12065 -0.3048)
			(stroke
				(width 0.1)
				(type default)
			)
			(layer "F.Fab")
		)
		(fp_line
			(start 0.12065 -0.3048)
			(end 0.67945 -0.3048)
			(stroke
				(width 0.1)
				(type default)
			)
			(layer "F.Fab")
		)
		(fp_line
			(start 0.67945 -0.3048)
			(end 0.67945 0.3048)
			(stroke
				(width 0.1)
				(type default)
			)
			(layer "F.Fab")
		)
		(fp_line
			(start -0.67945 -0.305054)
			(end -0.12065 -0.305054)
			(stroke
				(width 0.1)
				(type default)
			)
			(layer "F.Fab")
		)
		(fp_line
			(start -0.12065 -0.305054)
			(end -0.12065 -0.2794)
			(stroke
				(width 0.1)
				(type default)
			)
			(layer "F.Fab")
		)
		(pad "1" smd circle
			(at -0.40005 0 270)
			(size 0 0)
			(layers "F.Cu" "F.Mask" "F.Paste")
			(net "PVCCIN_CPU0")
		)
		(pad "2" smd circle
			(at 0.40005 0 270)
			(size 0 0)
			(layers "F.Cu" "F.Mask" "F.Paste")
			(net "GND")
		)
	)
	(footprint ""
		(layer "F.Cu")
		(at 112.33531 -74.908156 -90)
		(property "Reference" "R3101"
			(at 0 0 270)
			(layer "F.SilkS")
			(hide yes)
			(effects
				(font
					(size 1.27 1.27)
				)
			)
		)
		(property "Value" ""
			(at 0 0 270)
			(layer "F.Fab")
			(effects
				(font
					(size 1.27 1.27)
				)
			)
		)
		(duplicate_pad_numbers_are_jumpers no)
		(fp_line
			(start -0.7874 0.4064)
			(end -0.7874 -0.4064)
			(stroke
				(width 0.1524)
				(type default)
			)
			(layer "F.SilkS")
		)
		(fp_line
			(start 0.7874 0.4064)
			(end -0.7874 0.4064)
			(stroke
				(width 0.1524)
				(type default)
			)
			(layer "F.SilkS")
		)
		(fp_line
			(start -0.7874 -0.4064)
			(end 0.7874 -0.4064)
			(stroke
				(width 0.1524)
				(type default)
			)
			(layer "F.SilkS")
		)
		(fp_line
			(start 0.7874 -0.4064)
			(end 0.7874 0.4064)
			(stroke
				(width 0.1524)
				(type default)
			)
			(layer "F.SilkS")
		)
		(fp_line
			(start -0.67945 0.3048)
			(end -0.67945 -0.305054)
			(stroke
				(width 0.1)
				(type default)
			)
			(layer "F.Fab")
		)
		(fp_line
			(start -0.12065 0.3048)
			(end -0.67945 0.3048)
			(stroke
				(width 0.1)
				(type default)
			)
			(layer "F.Fab")
		)
		(fp_line
			(start 0.120396 0.3048)
			(end 0.120396 0.2794)
			(stroke
				(width 0.1)
				(type default)
			)
			(layer "F.Fab")
		)
		(fp_line
			(start 0.67945 0.3048)
			(end 0.120396 0.3048)
			(stroke
				(width 0.1)
				(type default)
			)
			(layer "F.Fab")
		)
		(fp_line
			(start -0.12065 0.2794)
			(end -0.12065 0.3048)
			(stroke
				(width 0.1)
				(type default)
			)
			(layer "F.Fab")
		)
		(fp_line
			(start 0.120396 0.2794)
			(end -0.12065 0.2794)
			(stroke
				(width 0.1)
				(type default)
			)
			(layer "F.Fab")
		)
		(fp_line
			(start -0.12065 -0.2794)
			(end 0.12065 -0.2794)
			(stroke
				(width 0.1)
				(type default)
			)
			(layer "F.Fab")
		)
		(fp_line
			(start 0.12065 -0.2794)
			(end 0.12065 -0.3048)
			(stroke
				(width 0.1)
				(type default)
			)
			(layer "F.Fab")
		)
		(fp_line
			(start 0.12065 -0.3048)
			(end 0.67945 -0.3048)
			(stroke
				(width 0.1)
				(type default)
			)
			(layer "F.Fab")
		)
		(fp_line
			(start 0.67945 -0.3048)
			(end 0.67945 0.3048)
			(stroke
				(width 0.1)
				(type default)
			)
			(layer "F.Fab")
		)
		(fp_line
			(start -0.67945 -0.305054)
			(end -0.12065 -0.305054)
			(stroke
				(width 0.1)
				(type default)
			)
			(layer "F.Fab")
		)
		(fp_line
			(start -0.12065 -0.305054)
			(end -0.12065 -0.2794)
			(stroke
				(width 0.1)
				(type default)
			)
			(layer "F.Fab")
		)
		(pad "1" smd circle
			(at -0.40005 0 270)
			(size 0 0)
			(layers "F.Cu" "F.Mask" "F.Paste")
			(net "LED_P5V_AUX")
		)
		(pad "2" smd circle
			(at 0.40005 0 270)
			(size 0 0)
			(layers "F.Cu" "F.Mask" "F.Paste")
			(net "P5V_AUX")
		)
	)
	(footprint ""
		(layer "F.Cu")
		(at 352.281744 -241.976656 -90)
		(property "Reference" "C1011"
			(at 0 0 270)
			(layer "F.SilkS")
			(hide yes)
			(effects
				(font
					(size 1.27 1.27)
				)
			)
		)
		(property "Value" ""
			(at 0 0 270)
			(layer "F.Fab")
			(effects
				(font
					(size 1.27 1.27)
				)
			)
		)
		(duplicate_pad_numbers_are_jumpers no)
		(fp_line
			(start -0.7874 0.4064)
			(end -0.7874 -0.4064)
			(stroke
				(width 0.1524)
				(type default)
			)
			(layer "F.SilkS")
		)
		(fp_line
			(start 0.7874 0.4064)
			(end -0.7874 0.4064)
			(stroke
				(width 0.1524)
				(type default)
			)
			(layer "F.SilkS")
		)
		(fp_line
			(start -0.7874 -0.4064)
			(end 0.7874 -0.4064)
			(stroke
				(width 0.1524)
				(type default)
			)
			(layer "F.SilkS")
		)
		(fp_line
			(start 0.7874 -0.4064)
			(end 0.7874 0.4064)
			(stroke
				(width 0.1524)
				(type default)
			)
			(layer "F.SilkS")
		)
		(fp_line
			(start -0.67945 0.3048)
			(end -0.67945 -0.305054)
			(stroke
				(width 0.1)
				(type default)
			)
			(layer "F.Fab")
		)
		(fp_line
			(start -0.12065 0.3048)
			(end -0.67945 0.3048)
			(stroke
				(width 0.1)
				(type default)
			)
			(layer "F.Fab")
		)
		(fp_line
			(start 0.120396 0.3048)
			(end 0.120396 0.2794)
			(stroke
				(width 0.1)
				(type default)
			)
			(layer "F.Fab")
		)
		(fp_line
			(start 0.67945 0.3048)
			(end 0.120396 0.3048)
			(stroke
				(width 0.1)
				(type default)
			)
			(layer "F.Fab")
		)
		(fp_line
			(start -0.12065 0.2794)
			(end -0.12065 0.3048)
			(stroke
				(width 0.1)
				(type default)
			)
			(layer "F.Fab")
		)
		(fp_line
			(start 0.120396 0.2794)
			(end -0.12065 0.2794)
			(stroke
				(width 0.1)
				(type default)
			)
			(layer "F.Fab")
		)
		(fp_line
			(start -0.12065 -0.2794)
			(end 0.12065 -0.2794)
			(stroke
				(width 0.1)
				(type default)
			)
			(layer "F.Fab")
		)
		(fp_line
			(start 0.12065 -0.2794)
			(end 0.12065 -0.3048)
			(stroke
				(width 0.1)
				(type default)
			)
			(layer "F.Fab")
		)
		(fp_line
			(start 0.12065 -0.3048)
			(end 0.67945 -0.3048)
			(stroke
				(width 0.1)
				(type default)
			)
			(layer "F.Fab")
		)
		(fp_line
			(start 0.67945 -0.3048)
			(end 0.67945 0.3048)
			(stroke
				(width 0.1)
				(type default)
			)
			(layer "F.Fab")
		)
		(fp_line
			(start -0.67945 -0.305054)
			(end -0.12065 -0.305054)
			(stroke
				(width 0.1)
				(type default)
			)
			(layer "F.Fab")
		)
		(fp_line
			(start -0.12065 -0.305054)
			(end -0.12065 -0.2794)
			(stroke
				(width 0.1)
				(type default)
			)
			(layer "F.Fab")
		)
		(pad "1" smd circle
			(at -0.40005 0 270)
			(size 0 0)
			(layers "F.Cu" "F.Mask" "F.Paste")
			(net "PVCCIN_CPU0")
		)
		(pad "2" smd circle
			(at 0.40005 0 270)
			(size 0 0)
			(layers "F.Cu" "F.Mask" "F.Paste")
			(net "GND")
		)
	)
)
